#ISCELL
  pure_quanta quanta_title_block_c *
  *
#ISCELL
  standard tap *
  page61_i1
#ISCELL
  standard tap *
  page61_i10
#ISCELL
  standard tap *
  page61_i100
#ISCELL
  standard tap *
  page61_i101
#ISCELL
  standard tap *
  page61_i102
#ISCELL
  standard offpage *
  page61_i103
#ISCELL
  standard offpage *
  page61_i104
#ISCELL
  standard tap *
  page61_i11
#CELL
  pure_quanta socket4677_azif0045p001c01cs *
  page61_i12
#ISCELL
  standard tap *
  page61_i13
#ISCELL
  standard offpage *
  page61_i14
#ISCELL
  standard offpage *
  page61_i15
#ISCELL
  standard tap *
  page61_i16
#ISCELL
  standard tap *
  page61_i17
#ISCELL
  standard tap *
  page61_i18
#ISCELL
  standard tap *
  page61_i19
#ISCELL
  standard tap *
  page61_i2
#ISCELL
  standard tap *
  page61_i20
#ISCELL
  standard tap *
  page61_i21
#ISCELL
  standard tap *
  page61_i22
#ISCELL
  standard offpage *
  page61_i223
#ISCELL
  standard offpage *
  page61_i224
#ISCELL
  standard tap *
  page61_i225
#ISCELL
  standard tap *
  page61_i226
#ISCELL
  standard tap *
  page61_i227
#ISCELL
  standard tap *
  page61_i228
#ISCELL
  standard tap *
  page61_i229
#ISCELL
  standard tap *
  page61_i23
#ISCELL
  standard tap *
  page61_i230
#ISCELL
  standard tap *
  page61_i231
#ISCELL
  standard tap *
  page61_i232
#ISCELL
  standard tap *
  page61_i233
#ISCELL
  standard tap *
  page61_i234
#ISCELL
  standard tap *
  page61_i235
#ISCELL
  standard tap *
  page61_i236
#ISCELL
  standard tap *
  page61_i237
#ISCELL
  standard tap *
  page61_i238
#ISCELL
  standard tap *
  page61_i239
#ISCELL
  standard tap *
  page61_i24
#ISCELL
  standard tap *
  page61_i240
#ISCELL
  standard tap *
  page61_i241
#ISCELL
  standard tap *
  page61_i242
#ISCELL
  standard tap *
  page61_i243
#ISCELL
  standard tap *
  page61_i244
#ISCELL
  standard tap *
  page61_i245
#ISCELL
  standard tap *
  page61_i246
#ISCELL
  standard tap *
  page61_i247
#ISCELL
  standard tap *
  page61_i248
#ISCELL
  standard tap *
  page61_i249
#ISCELL
  standard tap *
  page61_i25
#ISCELL
  standard tap *
  page61_i250
#ISCELL
  standard tap *
  page61_i251
#ISCELL
  standard tap *
  page61_i252
#ISCELL
  standard tap *
  page61_i253
#ISCELL
  standard tap *
  page61_i254
#ISCELL
  standard tap *
  page61_i255
#ISCELL
  standard tap *
  page61_i256
#ISCELL
  standard tap *
  page61_i257
#ISCELL
  standard tap *
  page61_i258
#ISCELL
  standard tap *
  page61_i259
#ISCELL
  standard tap *
  page61_i26
#ISCELL
  standard tap *
  page61_i260
#ISCELL
  standard tap *
  page61_i261
#ISCELL
  standard tap *
  page61_i262
#ISCELL
  standard tap *
  page61_i263
#ISCELL
  standard tap *
  page61_i264
#ISCELL
  standard tap *
  page61_i265
#ISCELL
  standard tap *
  page61_i266
#ISCELL
  standard tap *
  page61_i267
#ISCELL
  standard tap *
  page61_i268
#ISCELL
  standard tap *
  page61_i269
#ISCELL
  standard tap *
  page61_i27
#ISCELL
  standard tap *
  page61_i270
#ISCELL
  standard tap *
  page61_i271
#ISCELL
  standard tap *
  page61_i272
#ISCELL
  standard tap *
  page61_i273
#ISCELL
  standard tap *
  page61_i274
#ISCELL
  standard tap *
  page61_i275
#ISCELL
  standard tap *
  page61_i276
#ISCELL
  standard tap *
  page61_i277
#ISCELL
  standard tap *
  page61_i278
#ISCELL
  standard tap *
  page61_i279
#ISCELL
  standard tap *
  page61_i28
#ISCELL
  standard tap *
  page61_i280
#ISCELL
  standard tap *
  page61_i281
#ISCELL
  standard tap *
  page61_i282
#ISCELL
  standard tap *
  page61_i283
#ISCELL
  standard tap *
  page61_i284
#ISCELL
  standard tap *
  page61_i285
#ISCELL
  standard tap *
  page61_i286
#ISCELL
  standard tap *
  page61_i287
#ISCELL
  standard offpage *
  page61_i288
#ISCELL
  standard offpage *
  page61_i289
#ISCELL
  standard tap *
  page61_i29
#ISCELL
  standard tap *
  page61_i290
#ISCELL
  standard tap *
  page61_i3
#ISCELL
  standard tap *
  page61_i30
#ISCELL
  standard tap *
  page61_i31
#ISCELL
  standard tap *
  page61_i32
#ISCELL
  standard tap *
  page61_i33
#ISCELL
  standard tap *
  page61_i34
#ISCELL
  standard tap *
  page61_i35
#ISCELL
  standard tap *
  page61_i4
#ISCELL
  standard tap *
  page61_i5
#CELL
  pure_quanta socket4677_azif0045p001c01cs *
  page61_i54
#ISCELL
  standard tap *
  page61_i6
#ISCELL
  standard tap *
  page61_i7
#ISCELL
  standard tap *
  page61_i71
#ISCELL
  standard tap *
  page61_i72
#ISCELL
  standard tap *
  page61_i73
#ISCELL
  standard tap *
  page61_i74
#ISCELL
  standard tap *
  page61_i75
#ISCELL
  standard tap *
  page61_i76
#ISCELL
  standard tap *
  page61_i77
#ISCELL
  standard tap *
  page61_i78
#ISCELL
  standard tap *
  page61_i79
#ISCELL
  standard tap *
  page61_i8
#ISCELL
  standard tap *
  page61_i80
#ISCELL
  standard tap *
  page61_i81
#ISCELL
  standard tap *
  page61_i82
#ISCELL
  standard tap *
  page61_i83
#ISCELL
  standard tap *
  page61_i84
#ISCELL
  standard tap *
  page61_i85
#ISCELL
  standard tap *
  page61_i86
#ISCELL
  standard tap *
  page61_i87
#ISCELL
  standard tap *
  page61_i88
#ISCELL
  standard tap *
  page61_i89
#ISCELL
  standard tap *
  page61_i9
#ISCELL
  standard tap *
  page61_i90
#ISCELL
  standard tap *
  page61_i91
#ISCELL
  standard tap *
  page61_i92
#ISCELL
  standard tap *
  page61_i93
#ISCELL
  standard tap *
  page61_i94
#ISCELL
  standard tap *
  page61_i95
#ISCELL
  standard tap *
  page61_i96
#ISCELL
  standard tap *
  page61_i97
#ISCELL
  standard tap *
  page61_i98
#ISCELL
  standard tap *
  page61_i99
